# SCM (Grand Teton) — schematic netlist excerpt (pin names and nets, part order shuffled) for the footprints in the layout excerpt that follows; sources: Cadence DE-HDL packaged netlist, KiCad conversion of 12092022_DA0F0TMDCD0_F0T_Management_Board_D_brd_V3_OCP.brd

R746  Q_RES  0 5% CHIP  pkg 0402LF  page 36 : A = IRQ_PCH_TPM_SPI_N ; B = IRQ_PCH_TPM_SPI_R2_N
R505  Q_RES  0 5% CHIP  pkg 0402LF  page 46 : A = IRQ_PCH_TPM_SPI_N ; B = IRQ_PCH_TPM_SPI_R_N

(kicad_pcb
	(version 20260206)
	(generator "pcbnew")
	(generator_version "10.0")
	(general
		(thickness 1.6)
		(legacy_teardrops no)
	)
	(paper "A4")
	(title_block
		(title "12092022_DA0F0TMDCD0_F0T_Management_Board_D_brd_V3_OCP.brd")
		(comment 1 "Grand Teton / footprints 90-91 of 1440")
	)
	(layers
		(0 "F.Cu" signal "TOP")
		(4 "In1.Cu" signal "GND")
		(6 "In2.Cu" signal "IN1")
		(8 "In3.Cu" signal "GND1")
		(10 "In4.Cu" signal "IN2")
		(12 "In5.Cu" signal "VCC")
		(14 "In6.Cu" signal "VCC1")
		(16 "In7.Cu" signal "IN3")
		(18 "In8.Cu" signal "GND2")
		(20 "In9.Cu" signal "IN4")
		(22 "In10.Cu" signal "GND3")
		(2 "B.Cu" signal "BOTTOM")
		(9 "F.Adhes" user "F.Adhesive")
		(11 "B.Adhes" user "B.Adhesive")
		(13 "F.Paste" user "Package Geometry/Pastemask Top")
		(15 "B.Paste" user "Package Geometry/Pastemask Bottom")
		(5 "F.SilkS" user "Ref Des/Silkscreen Top")
		(7 "B.SilkS" user "Ref Des/Silkscreen Bottom")
		(1 "F.Mask" user "Board Geometry/Soldermask Top")
		(3 "B.Mask" user "Board Geometry/Soldermask Bottom")
		(17 "Dwgs.User" user "User.Drawings")
		(19 "Cmts.User" user "User.Comments")
		(21 "Eco1.User" user "User.Eco1")
		(23 "Eco2.User" user "User.Eco2")
		(25 "Edge.Cuts" user "Board Geometry/Outline")
		(27 "Margin" user)
		(31 "F.CrtYd" user "Package Geometry/Place Bound Top")
		(29 "B.CrtYd" user "Package Geometry/Place Bound Bottom")
		(35 "F.Fab" user "Ref Des/Assembly Top")
		(33 "B.Fab" user "Ref Des/Assembly Bottom")
	)
	(footprint ""
		(layer "F.Cu")
		(at 22.479 -102.743 -90)
		(property "Reference" "R746"
			(at 0 0 270)
			(layer "F.SilkS")
			(hide yes)
			(effects
				(font
					(size 1.27 1.27)
				)
			)
		)
		(property "Value" ""
			(at 0 0 270)
			(layer "F.Fab")
			(effects
				(font
					(size 1.27 1.27)
				)
			)
		)
		(duplicate_pad_numbers_are_jumpers no)
		(fp_line
			(start -0.7874 0.4064)
			(end -0.7874 -0.4064)
			(stroke
				(width 0.1524)
				(type default)
			)
			(layer "F.SilkS")
		)
		(fp_line
			(start 0.7874 0.4064)
			(end -0.7874 0.4064)
			(stroke
				(width 0.1524)
				(type default)
			)
			(layer "F.SilkS")
		)
		(fp_line
			(start -0.7874 -0.4064)
			(end 0.7874 -0.4064)
			(stroke
				(width 0.1524)
				(type default)
			)
			(layer "F.SilkS")
		)
		(fp_line
			(start 0.7874 -0.4064)
			(end 0.7874 0.4064)
			(stroke
				(width 0.1524)
				(type default)
			)
			(layer "F.SilkS")
		)
		(fp_line
			(start -0.67945 0.3048)
			(end -0.67945 -0.305054)
			(stroke
				(width 0.1)
				(type default)
			)
			(layer "F.Fab")
		)
		(fp_line
			(start -0.12065 0.3048)
			(end -0.67945 0.3048)
			(stroke
				(width 0.1)
				(type default)
			)
			(layer "F.Fab")
		)
		(fp_line
			(start 0.120396 0.3048)
			(end 0.120396 0.2794)
			(stroke
				(width 0.1)
				(type default)
			)
			(layer "F.Fab")
		)
		(fp_line
			(start 0.67945 0.3048)
			(end 0.120396 0.3048)
			(stroke
				(width 0.1)
				(type default)
			)
			(layer "F.Fab")
		)
		(fp_line
			(start -0.12065 0.2794)
			(end -0.12065 0.3048)
			(stroke
				(width 0.1)
				(type default)
			)
			(layer "F.Fab")
		)
		(fp_line
			(start 0.120396 0.2794)
			(end -0.12065 0.2794)
			(stroke
				(width 0.1)
				(type default)
			)
			(layer "F.Fab")
		)
		(fp_line
			(start -0.12065 -0.2794)
			(end 0.12065 -0.2794)
			(stroke
				(width 0.1)
				(type default)
			)
			(layer "F.Fab")
		)
		(fp_line
			(start 0.12065 -0.2794)
			(end 0.12065 -0.3048)
			(stroke
				(width 0.1)
				(type default)
			)
			(layer "F.Fab")
		)
		(fp_line
			(start 0.12065 -0.3048)
			(end 0.67945 -0.3048)
			(stroke
				(width 0.1)
				(type default)
			)
			(layer "F.Fab")
		)
		(fp_line
			(start 0.67945 -0.3048)
			(end 0.67945 0.3048)
			(stroke
				(width 0.1)
				(type default)
			)
			(layer "F.Fab")
		)
		(fp_line
			(start -0.67945 -0.305054)
			(end -0.12065 -0.305054)
			(stroke
				(width 0.1)
				(type default)
			)
			(layer "F.Fab")
		)
		(fp_line
			(start -0.12065 -0.305054)
			(end -0.12065 -0.2794)
			(stroke
				(width 0.1)
				(type default)
			)
			(layer "F.Fab")
		)
		(pad "1" smd circle
			(at -0.40005 0 270)
			(size 0 0)
			(layers "F.Cu" "F.Mask" "F.Paste")
			(net "IRQ_PCH_TPM_SPI_N")
		)
		(pad "2" smd circle
			(at 0.40005 0 270)
			(size 0 0)
			(layers "F.Cu" "F.Mask" "F.Paste")
			(net "IRQ_PCH_TPM_SPI_R2_N")
		)
	)
	(footprint ""
		(layer "F.Cu")
		(at 57.5691 -95.96374 90)
		(property "Reference" "R505"
			(at 0 0 90)
			(layer "F.SilkS")
			(hide yes)
			(effects
				(font
					(size 1.27 1.27)
				)
			)
		)
		(property "Value" ""
			(at 0 0 90)
			(layer "F.Fab")
			(effects
				(font
					(size 1.27 1.27)
				)
			)
		)
		(duplicate_pad_numbers_are_jumpers no)
		(fp_line
			(start 0.7874 -0.4064)
			(end 0.7874 0.4064)
			(stroke
				(width 0.1524)
				(type default)
			)
			(layer "F.SilkS")
		)
		(fp_line
			(start -0.7874 -0.4064)
			(end 0.7874 -0.4064)
			(stroke
				(width 0.1524)
				(type default)
			)
			(layer "F.SilkS")
		)
		(fp_line
			(start 0.7874 0.4064)
			(end -0.7874 0.4064)
			(stroke
				(width 0.1524)
				(type default)
			)
			(layer "F.SilkS")
		)
		(fp_line
			(start -0.7874 0.4064)
			(end -0.7874 -0.4064)
			(stroke
				(width 0.1524)
				(type default)
			)
			(layer "F.SilkS")
		)
		(fp_line
			(start -0.12065 -0.305054)
			(end -0.12065 -0.2794)
			(stroke
				(width 0.1)
				(type default)
			)
			(layer "F.Fab")
		)
		(fp_line
			(start -0.67945 -0.305054)
			(end -0.12065 -0.305054)
			(stroke
				(width 0.1)
				(type default)
			)
			(layer "F.Fab")
		)
		(fp_line
			(start 0.67945 -0.3048)
			(end 0.67945 0.3048)
			(stroke
				(width 0.1)
				(type default)
			)
			(layer "F.Fab")
		)
		(fp_line
			(start 0.12065 -0.3048)
			(end 0.67945 -0.3048)
			(stroke
				(width 0.1)
				(type default)
			)
			(layer "F.Fab")
		)
		(fp_line
			(start 0.12065 -0.2794)
			(end 0.12065 -0.3048)
			(stroke
				(width 0.1)
				(type default)
			)
			(layer "F.Fab")
		)
		(fp_line
			(start -0.12065 -0.2794)
			(end 0.12065 -0.2794)
			(stroke
				(width 0.1)
				(type default)
			)
			(layer "F.Fab")
		)
		(fp_line
			(start 0.120396 0.2794)
			(end -0.12065 0.2794)
			(stroke
				(width 0.1)
				(type default)
			)
			(layer "F.Fab")
		)
		(fp_line
			(start -0.12065 0.2794)
			(end -0.12065 0.3048)
			(stroke
				(width 0.1)
				(type default)
			)
			(layer "F.Fab")
		)
		(fp_line
			(start 0.67945 0.3048)
			(end 0.120396 0.3048)
			(stroke
				(width 0.1)
				(type default)
			)
			(layer "F.Fab")
		)
		(fp_line
			(start 0.120396 0.3048)
			(end 0.120396 0.2794)
			(stroke
				(width 0.1)
				(type default)
			)
			(layer "F.Fab")
		)
		(fp_line
			(start -0.12065 0.3048)
			(end -0.67945 0.3048)
			(stroke
				(width 0.1)
				(type default)
			)
			(layer "F.Fab")
		)
		(fp_line
			(start -0.67945 0.3048)
			(end -0.67945 -0.305054)
			(stroke
				(width 0.1)
				(type default)
			)
			(layer "F.Fab")
		)
		(pad "1" smd circle
			(at -0.40005 0 90)
			(size 0 0)
			(layers "F.Cu" "F.Mask" "F.Paste")
			(net "IRQ_PCH_TPM_SPI_N")
		)
		(pad "2" smd circle
			(at 0.40005 0 90)
			(size 0 0)
			(layers "F.Cu" "F.Mask" "F.Paste")
			(net "IRQ_PCH_TPM_SPI_R_N")
		)
	)
)
